# T6G (Grand Teton) — schematic netlist excerpt (pin names and nets, part order shuffled) for the footprints in the layout excerpt that follows; sources: Cadence DE-HDL packaged netlist, KiCad conversion of 04192023_DAF0TMB3IC0_F0TG_MB_C_brd_V02_OCP.brd

J111  CONN112_10137002101LF  CONN112_10137002-101LF IO  pkg HSD_F112D8_P2W1-2_RDH  page 121
  A1  = GPU_PEX_STRAP1
  A2  = GND
  A3  = GPU_BASE_ID0
  A4  = GND
  A5  = GPU_PEX_STRAP0
  A6  = GND
  A7  = GPU_FPGA_RST_R_BUF_N
  A8  = GND
  B1  = GND
  B2  = P5E_CPU1_P0_RX_BUF_DN<9>
  B3  = GND
  B4  = P5E_CPU1_P0_RX_BUF_DN<11>
  B5  = GND
  B6  = P5E_CPU1_P0_RX_BUF_DN<13>
  B7  = GND
  B8  = P5E_CPU1_P0_RX_BUF_DN<15>
  C1  = P5E_CPU1_P0_RX_BUF_DN<8>
  C2  = P5E_CPU1_P0_RX_BUF_DP<9>
  C3  = P5E_CPU1_P0_RX_BUF_DN<10>
  C4  = P5E_CPU1_P0_RX_BUF_DP<11>
  C5  = P5E_CPU1_P0_RX_BUF_DN<12>
  C6  = P5E_CPU1_P0_RX_BUF_DP<13>
  C7  = P5E_CPU1_P0_RX_BUF_DN<14>
  C8  = P5E_CPU1_P0_RX_BUF_DP<15>
  D1  = P5E_CPU1_P0_RX_BUF_DP<8>
  D2  = GND
  D3  = P5E_CPU1_P0_RX_BUF_DP<10>
  D4  = GND
  D5  = P5E_CPU1_P0_RX_BUF_DP<12>
  D6  = GND
  D7  = P5E_CPU1_P0_RX_BUF_DP<14>
  D8  = GND
  E1  = GND
  E2  = P5E_CPU1_P1_RX_BUF_DN<9>
  E3  = GND
  E4  = P5E_CPU1_P1_RX_BUF_DN<11>
  E5  = GND
  E6  = P5E_CPU1_P1_RX_BUF_DN<13>
  E7  = GND
  E8  = P5E_CPU1_P1_RX_BUF_DN<15>
  F1  = P5E_CPU1_P1_RX_BUF_DN<8>
  F2  = P5E_CPU1_P1_RX_BUF_DP<9>
  F3  = P5E_CPU1_P1_RX_BUF_DN<10>
  F4  = P5E_CPU1_P1_RX_BUF_DP<11>
  F5  = P5E_CPU1_P1_RX_BUF_DN<12>
  F6  = P5E_CPU1_P1_RX_BUF_DP<13>
  F7  = P5E_CPU1_P1_RX_BUF_DN<14>
  F8  = P5E_CPU1_P1_RX_BUF_DP<15>
  G1  = P5E_CPU1_P1_RX_BUF_DP<8>
  G2  = GND
  G3  = P5E_CPU1_P1_RX_BUF_DP<10>
  G4  = GND
  G5  = P5E_CPU1_P1_RX_BUF_DP<12>
  G6  = GND
  G7  = P5E_CPU1_P1_RX_BUF_DP<14>
  G8  = GND
  H1  = GND
  H2  = P5E_CPU1_P0_TX_BUF_C_DN<9>
  H3  = GND
  H4  = P5E_CPU1_P0_TX_BUF_C_DN<11>
  H5  = GND
  H6  = P5E_CPU1_P0_TX_BUF_C_DN<13>
  H7  = GND
  H8  = P5E_CPU1_P0_TX_BUF_C_DN<15>
  I1  = P5E_CPU1_P0_TX_BUF_C_DN<8>
  I2  = P5E_CPU1_P0_TX_BUF_C_DP<9>
  I3  = P5E_CPU1_P0_TX_BUF_C_DN<10>
  I4  = P5E_CPU1_P0_TX_BUF_C_DP<11>
  I5  = P5E_CPU1_P0_TX_BUF_C_DN<12>
  I6  = P5E_CPU1_P0_TX_BUF_C_DP<13>
  I7  = P5E_CPU1_P0_TX_BUF_C_DN<14>
  I8  = P5E_CPU1_P0_TX_BUF_C_DP<15>
  J1  = P5E_CPU1_P0_TX_BUF_C_DP<8>
  J2  = GND
  J3  = P5E_CPU1_P0_TX_BUF_C_DP<10>
  J4  = GND
  J5  = P5E_CPU1_P0_TX_BUF_C_DP<12>
  J6  = GND
  J7  = P5E_CPU1_P0_TX_BUF_C_DP<14>
  J8  = GND
  K1  = GND
  K2  = P5E_CPU1_P1_TX_BUF_C_DN<9>
  K3  = GND
  K4  = P5E_CPU1_P1_TX_BUF_C_DN<11>
  K5  = GND
  K6  = P5E_CPU1_P1_TX_BUF_C_DN<13>
  K7  = GND
  K8  = P5E_CPU1_P1_TX_BUF_C_DN<15>
  L1  = P5E_CPU1_P1_TX_BUF_C_DN<8>
  L2  = P5E_CPU1_P1_TX_BUF_C_DP<9>
  L3  = P5E_CPU1_P1_TX_BUF_C_DN<10>
  L4  = P5E_CPU1_P1_TX_BUF_C_DP<11>
  L5  = P5E_CPU1_P1_TX_BUF_C_DN<12>
  L6  = P5E_CPU1_P1_TX_BUF_C_DP<13>
  L7  = P5E_CPU1_P1_TX_BUF_C_DN<14>
  L8  = P5E_CPU1_P1_TX_BUF_C_DP<15>
  M1  = P5E_CPU1_P1_TX_BUF_C_DP<8>
  M2  = GND
  M3  = P5E_CPU1_P1_TX_BUF_C_DP<10>
  M4  = GND
  M5  = P5E_CPU1_P1_TX_BUF_C_DP<12>
  M6  = GND
  M7  = P5E_CPU1_P1_TX_BUF_C_DP<14>
  M8  = GND
  N1  = GND
  N2  = GPU_PRSNT_N
  N3  = GND
  N4  = FM_GPU_PWR_EN_R_BUF
  N5  = GND
  N6  = FM_GPU_PWRGD
  N7  = GND
  N8  = GPU_BASE_ID1

(kicad_pcb
	(version 20260206)
	(generator "pcbnew")
	(generator_version "10.0")
	(general
		(thickness 1.6)
		(legacy_teardrops no)
	)
	(paper "A4")
	(title_block
		(title "04192023_DAF0TMB3IC0_F0TG_MB_C_brd_V02_OCP.brd")
		(comment 1 "Grand Teton / footprint 2176 of 8354 (J111), pads 1-31 of 48")
	)
	(layers
		(0 "F.Cu" signal "TOP")
		(4 "In1.Cu" signal "GND")
		(6 "In2.Cu" signal "IN1")
		(8 "In3.Cu" signal "GND1")
		(10 "In4.Cu" signal "IN2")
		(12 "In5.Cu" signal "GND2")
		(14 "In6.Cu" signal "IN3")
		(16 "In7.Cu" signal "GND3")
		(18 "In8.Cu" signal "VCC")
		(20 "In9.Cu" signal "VCC1")
		(22 "In10.Cu" signal "GND4")
		(24 "In11.Cu" signal "IN4")
		(26 "In12.Cu" signal "GND5")
		(28 "In13.Cu" signal "IN5")
		(30 "In14.Cu" signal "GND6")
		(32 "In15.Cu" signal "IN6")
		(34 "In16.Cu" signal "GND7")
		(2 "B.Cu" signal "BOTTOM")
		(9 "F.Adhes" user "F.Adhesive")
		(11 "B.Adhes" user "B.Adhesive")
		(13 "F.Paste" user "Package Geometry/Pastemask Top")
		(15 "B.Paste" user "Package Geometry/Pastemask Bottom")
		(5 "F.SilkS" user "Ref Des/Silkscreen Top")
		(7 "B.SilkS" user "Ref Des/Silkscreen Bottom")
		(1 "F.Mask" user "Board Geometry/Soldermask Top")
		(3 "B.Mask" user "Board Geometry/Soldermask Bottom")
		(17 "Dwgs.User" user "User.Drawings")
		(19 "Cmts.User" user "User.Comments")
		(21 "Eco1.User" user "User.Eco1")
		(23 "Eco2.User" user "User.Eco2")
		(25 "Edge.Cuts" user "Board Geometry/Outline")
		(27 "Margin" user)
		(31 "F.CrtYd" user "Package Geometry/Place Bound Top")
		(29 "B.CrtYd" user "Package Geometry/Place Bound Bottom")
		(35 "F.Fab" user "Ref Des/Assembly Top")
		(33 "B.Fab" user "Ref Des/Assembly Bottom")
	)
	(footprint ""
		(layer "F.Cu")
		(at 75.65009 -440.489848)
		(property "Reference" "J111"
			(at 14.3637 23.187152 0)
			(unlocked yes)
			(layer "F.SilkS")
			(effects
				(font
					(size 0.7874 0.5842)
					(thickness 0.1524)
				)
				(justify left)
			)
		)
		(property "Value" ""
			(at 0 0 0)
			(layer "F.Fab")
			(effects
				(font
					(size 1.27 1.27)
				)
			)
		)
		(duplicate_pad_numbers_are_jumpers no)
		(pad "A1" thru_hole rect
			(at 0 0 180)
			(size 0.766318 0.766318)
			(drill 0.359918)
			(layers "*.Cu" "*.Mask")
			(remove_unused_layers no)
			(net "GPU_PEX_STRAP1")
			(clearance 0.0508)
			(thermal_gap 0.0508)
			(padstack
				(mode front_inner_back)
				(layer "Inner"
					(shape circle)
					(size 0.766318 0.766318)
					(clearance 0.0508)
				)
				(layer "B.Cu"
					(shape rect)
					(size 0.766318 0.766318)
					(clearance 0.0508)
				)
			)
		)
		(pad "A2" thru_hole circle
			(at 1.999996 0.199898 180)
			(size 0.906272 0.906272)
			(drill 0.499872)
			(layers "*.Cu" "*.Mask")
			(remove_unused_layers no)
			(net "GND")
			(clearance 0.0508)
			(thermal_gap 0.0508)
		)
		(pad "A3" thru_hole circle
			(at 3.999992 0 180)
			(size 0.766318 0.766318)
			(drill 0.359918)
			(layers "*.Cu" "*.Mask")
			(remove_unused_layers no)
			(net "GPU_BASE_ID0")
			(clearance 0.0508)
			(thermal_gap 0.0508)
		)
		(pad "A4" thru_hole circle
			(at 5.999988 0.199898 180)
			(size 0.906272 0.906272)
			(drill 0.499872)
			(layers "*.Cu" "*.Mask")
			(remove_unused_layers no)
			(net "GND")
			(clearance 0.0508)
			(thermal_gap 0.0508)
		)
		(pad "A5" thru_hole circle
			(at 7.999984 0 180)
			(size 0.766318 0.766318)
			(drill 0.359918)
			(layers "*.Cu" "*.Mask")
			(remove_unused_layers no)
			(net "GPU_PEX_STRAP0")
			(clearance 0.0508)
			(thermal_gap 0.0508)
		)
		(pad "A6" thru_hole circle
			(at 9.99998 0.199898 180)
			(size 0.906272 0.906272)
			(drill 0.499872)
			(layers "*.Cu" "*.Mask")
			(remove_unused_layers no)
			(net "GND")
			(clearance 0.0508)
			(thermal_gap 0.0508)
		)
		(pad "A7" thru_hole circle
			(at 11.999976 0 180)
			(size 0.766318 0.766318)
			(drill 0.359918)
			(layers "*.Cu" "*.Mask")
			(remove_unused_layers no)
			(net "GPU_FPGA_RST_R_BUF_N")
			(clearance 0.0508)
			(thermal_gap 0.0508)
		)
		(pad "A8" thru_hole circle
			(at 13.999972 0.199898 180)
			(size 0.906272 0.906272)
			(drill 0.499872)
			(layers "*.Cu" "*.Mask")
			(remove_unused_layers no)
			(net "GND")
			(clearance 0.0508)
			(thermal_gap 0.0508)
		)
		(pad "B1" thru_hole circle
			(at 0 1.199896 180)
			(size 0.906272 0.906272)
			(drill 0.499872)
			(layers "*.Cu" "*.Mask")
			(remove_unused_layers no)
			(net "GND")
			(clearance 0.0508)
			(thermal_gap 0.0508)
		)
		(pad "B3" thru_hole circle
			(at 3.999992 1.199896 180)
			(size 0.906272 0.906272)
			(drill 0.499872)
			(layers "*.Cu" "*.Mask")
			(remove_unused_layers no)
			(net "GND")
			(clearance 0.0508)
			(thermal_gap 0.0508)
		)
		(pad "B5" thru_hole circle
			(at 7.999984 1.199896 180)
			(size 0.906272 0.906272)
			(drill 0.499872)
			(layers "*.Cu" "*.Mask")
			(remove_unused_layers no)
			(net "GND")
			(clearance 0.0508)
			(thermal_gap 0.0508)
		)
		(pad "B7" thru_hole circle
			(at 11.999976 1.199896 180)
			(size 0.906272 0.906272)
			(drill 0.499872)
			(layers "*.Cu" "*.Mask")
			(remove_unused_layers no)
			(net "GND")
			(clearance 0.0508)
			(thermal_gap 0.0508)
		)
		(pad "D2" thru_hole circle
			(at 1.999996 3.800094 180)
			(size 0.906272 0.906272)
			(drill 0.499872)
			(layers "*.Cu" "*.Mask")
			(remove_unused_layers no)
			(net "GND")
			(clearance 0.0508)
			(thermal_gap 0.0508)
		)
		(pad "D4" thru_hole circle
			(at 5.999988 3.800094 180)
			(size 0.906272 0.906272)
			(drill 0.499872)
			(layers "*.Cu" "*.Mask")
			(remove_unused_layers no)
			(net "GND")
			(clearance 0.0508)
			(thermal_gap 0.0508)
		)
		(pad "D6" thru_hole circle
			(at 9.99998 3.800094 180)
			(size 0.906272 0.906272)
			(drill 0.499872)
			(layers "*.Cu" "*.Mask")
			(remove_unused_layers no)
			(net "GND")
			(clearance 0.0508)
			(thermal_gap 0.0508)
		)
		(pad "D8" thru_hole circle
			(at 13.999972 3.800094 180)
			(size 0.906272 0.906272)
			(drill 0.499872)
			(layers "*.Cu" "*.Mask")
			(remove_unused_layers no)
			(net "GND")
			(clearance 0.0508)
			(thermal_gap 0.0508)
		)
		(pad "E1" thru_hole circle
			(at 0 4.800092 180)
			(size 0.906272 0.906272)
			(drill 0.499872)
			(layers "*.Cu" "*.Mask")
			(remove_unused_layers no)
			(net "GND")
			(clearance 0.0508)
			(thermal_gap 0.0508)
		)
		(pad "E3" thru_hole circle
			(at 3.999992 4.800092 180)
			(size 0.906272 0.906272)
			(drill 0.499872)
			(layers "*.Cu" "*.Mask")
			(remove_unused_layers no)
			(net "GND")
			(clearance 0.0508)
			(thermal_gap 0.0508)
		)
		(pad "E5" thru_hole circle
			(at 7.999984 4.800092 180)
			(size 0.906272 0.906272)
			(drill 0.499872)
			(layers "*.Cu" "*.Mask")
			(remove_unused_layers no)
			(net "GND")
			(clearance 0.0508)
			(thermal_gap 0.0508)
		)
		(pad "E7" thru_hole circle
			(at 11.999976 4.800092 180)
			(size 0.906272 0.906272)
			(drill 0.499872)
			(layers "*.Cu" "*.Mask")
			(remove_unused_layers no)
			(net "GND")
			(clearance 0.0508)
			(thermal_gap 0.0508)
		)
		(pad "G2" thru_hole circle
			(at 1.999996 7.400036 180)
			(size 0.906272 0.906272)
			(drill 0.499872)
			(layers "*.Cu" "*.Mask")
			(remove_unused_layers no)
			(net "GND")
			(clearance 0.0508)
			(thermal_gap 0.0508)
		)
		(pad "G4" thru_hole circle
			(at 5.999988 7.400036 180)
			(size 0.906272 0.906272)
			(drill 0.499872)
			(layers "*.Cu" "*.Mask")
			(remove_unused_layers no)
			(net "GND")
			(clearance 0.0508)
			(thermal_gap 0.0508)
		)
		(pad "G6" thru_hole circle
			(at 9.99998 7.400036 180)
			(size 0.906272 0.906272)
			(drill 0.499872)
			(layers "*.Cu" "*.Mask")
			(remove_unused_layers no)
			(net "GND")
			(clearance 0.0508)
			(thermal_gap 0.0508)
		)
		(pad "G8" thru_hole circle
			(at 13.999972 7.400036 180)
			(size 0.906272 0.906272)
			(drill 0.499872)
			(layers "*.Cu" "*.Mask")
			(remove_unused_layers no)
			(net "GND")
			(clearance 0.0508)
			(thermal_gap 0.0508)
		)
		(pad "H1" thru_hole circle
			(at 0 8.400034 180)
			(size 0.906272 0.906272)
			(drill 0.499872)
			(layers "*.Cu" "*.Mask")
			(remove_unused_layers no)
			(net "GND")
			(clearance 0.0508)
			(thermal_gap 0.0508)
		)
		(pad "H3" thru_hole circle
			(at 3.999992 8.400034 180)
			(size 0.906272 0.906272)
			(drill 0.499872)
			(layers "*.Cu" "*.Mask")
			(remove_unused_layers no)
			(net "GND")
			(clearance 0.0508)
			(thermal_gap 0.0508)
		)
		(pad "H5" thru_hole circle
			(at 7.999984 8.400034 180)
			(size 0.906272 0.906272)
			(drill 0.499872)
			(layers "*.Cu" "*.Mask")
			(remove_unused_layers no)
			(net "GND")
			(clearance 0.0508)
			(thermal_gap 0.0508)
		)
		(pad "H7" thru_hole circle
			(at 11.999976 8.400034 180)
			(size 0.906272 0.906272)
			(drill 0.499872)
			(layers "*.Cu" "*.Mask")
			(remove_unused_layers no)
			(net "GND")
			(clearance 0.0508)
			(thermal_gap 0.0508)
		)
		(pad "J2" thru_hole circle
			(at 1.999996 10.999978 180)
			(size 0.906272 0.906272)
			(drill 0.499872)
			(layers "*.Cu" "*.Mask")
			(remove_unused_layers no)
			(net "GND")
			(clearance 0.0508)
			(thermal_gap 0.0508)
		)
		(pad "J4" thru_hole circle
			(at 5.999988 10.999978 180)
			(size 0.906272 0.906272)
			(drill 0.499872)
			(layers "*.Cu" "*.Mask")
			(remove_unused_layers no)
			(net "GND")
			(clearance 0.0508)
			(thermal_gap 0.0508)
		)
		(pad "J6" thru_hole circle
			(at 9.99998 10.999978 180)
			(size 0.906272 0.906272)
			(drill 0.499872)
			(layers "*.Cu" "*.Mask")
			(remove_unused_layers no)
			(net "GND")
			(clearance 0.0508)
			(thermal_gap 0.0508)
		)
	)
)
